(kicad_pcb
	(version 20260206)
	(generator "pcbnew")
	(generator_version "10.0")
	(general
		(thickness 1.6)
		(legacy_teardrops no)
	)
	(paper "A4")
	(title_block
		(title "01162023_DA0F0TEBIF0_F0T_Expander_BD_F_brd_V02_OCP.brd")
		(comment 1 "Grand Teton / footprints 3127-3134 of 9728")
	)
	(layers
		(0 "F.Cu" signal "TOP")
		(4 "In1.Cu" signal "GND")
		(6 "In2.Cu" signal "VCC")
		(8 "In3.Cu" signal "VCC1")
		(10 "In4.Cu" signal "GND1")
		(12 "In5.Cu" signal "IN1")
		(14 "In6.Cu" signal "GND2")
		(16 "In7.Cu" signal "IN2")
		(18 "In8.Cu" signal "GND3")
		(20 "In9.Cu" signal "IN3")
		(22 "In10.Cu" signal "GND4")
		(24 "In11.Cu" signal "IN4")
		(26 "In12.Cu" signal "GND5")
		(28 "In13.Cu" signal "IN5")
		(30 "In14.Cu" signal "GND6")
		(32 "In15.Cu" signal "IN6")
		(34 "In16.Cu" signal "GND7")
		(2 "B.Cu" signal "BOTTOM")
		(9 "F.Adhes" user "F.Adhesive")
		(11 "B.Adhes" user "B.Adhesive")
		(13 "F.Paste" user "Package Geometry/Pastemask Top")
		(15 "B.Paste" user "Package Geometry/Pastemask Bottom")
		(5 "F.SilkS" user "Ref Des/Silkscreen Top")
		(7 "B.SilkS" user "Ref Des/Silkscreen Bottom")
		(1 "F.Mask" user "Board Geometry/Soldermask Top")
		(3 "B.Mask" user "Board Geometry/Soldermask Bottom")
		(17 "Dwgs.User" user "User.Drawings")
		(19 "Cmts.User" user "User.Comments")
		(21 "Eco1.User" user "User.Eco1")
		(23 "Eco2.User" user "User.Eco2")
		(25 "Edge.Cuts" user "Board Geometry/Outline")
		(27 "Margin" user)
		(31 "F.CrtYd" user "Package Geometry/Place Bound Top")
		(29 "B.CrtYd" user "Package Geometry/Place Bound Bottom")
		(35 "F.Fab" user "Ref Des/Assembly Top")
		(33 "B.Fab" user "Ref Des/Assembly Bottom")
	)
	(footprint ""
		(layer "F.Cu")
		(at 403.16658 -356.244906 90)
		(property "Reference" "C731"
			(at 0 0 90)
			(layer "F.SilkS")
			(hide yes)
			(effects
				(font
					(size 1.27 1.27)
				)
			)
		)
		(property "Value" ""
			(at 0 0 90)
			(layer "F.Fab")
			(effects
				(font
					(size 1.27 1.27)
				)
			)
		)
		(duplicate_pad_numbers_are_jumpers no)
		(fp_line
			(start 0.299974 -0.150114)
			(end 0.299974 0.150114)
			(stroke
				(width 0.1)
				(type default)
			)
			(layer "F.Fab")
		)
		(fp_line
			(start -0.299974 -0.150114)
			(end 0.299974 -0.150114)
			(stroke
				(width 0.1)
				(type default)
			)
			(layer "F.Fab")
		)
		(fp_line
			(start 0.299974 0.150114)
			(end -0.299974 0.150114)
			(stroke
				(width 0.1)
				(type default)
			)
			(layer "F.Fab")
		)
		(fp_line
			(start -0.299974 0.150114)
			(end -0.299974 -0.150114)
			(stroke
				(width 0.1)
				(type default)
			)
			(layer "F.Fab")
		)
		(pad "1" smd rect
			(at -0.2667 0 90)
			(size 0.3048 0.381)
			(layers "F.Cu" "F.Mask" "F.Paste")
			(net "P5E_PEX3_STN5_TX_DN<95>")
		)
		(pad "2" smd rect
			(at 0.2667 0 90)
			(size 0.3048 0.381)
			(layers "F.Cu" "F.Mask" "F.Paste")
			(net "P5E_PEX3_STN5_TX_C_DN<95>")
		)
	)
	(footprint ""
		(layer "F.Cu")
		(at 398.574006 -26.31186 -90)
		(property "Reference" "U409"
			(at 0.14986 -2.442464 90)
			(unlocked yes)
			(layer "F.SilkS")
			(effects
				(font
					(size 0.7874 0.5842)
					(thickness 0.1524)
				)
			)
		)
		(property "Value" ""
			(at 0 0 270)
			(layer "F.Fab")
			(effects
				(font
					(size 1.27 1.27)
				)
			)
		)
		(duplicate_pad_numbers_are_jumpers no)
		(fp_line
			(start -1.949958 1.610106)
			(end -1.949958 -1.610106)
			(stroke
				(width 0.1524)
				(type default)
			)
			(layer "F.SilkS")
		)
		(fp_line
			(start 1.949958 1.610106)
			(end -1.949958 1.610106)
			(stroke
				(width 0.1524)
				(type default)
			)
			(layer "F.SilkS")
		)
		(fp_line
			(start 1.949958 -1.560068)
			(end 1.949958 1.610106)
			(stroke
				(width 0.1524)
				(type default)
			)
			(layer "F.SilkS")
		)
		(fp_line
			(start -1.949958 -1.610106)
			(end 1.949958 -1.610106)
			(stroke
				(width 0.1524)
				(type default)
			)
			(layer "F.SilkS")
		)
		(fp_line
			(start -0.750062 1.560068)
			(end -0.750062 -1.560068)
			(stroke
				(width 0.1)
				(type default)
			)
			(layer "F.Fab")
		)
		(fp_line
			(start 0.750062 1.560068)
			(end -0.750062 1.560068)
			(stroke
				(width 0.1)
				(type default)
			)
			(layer "F.Fab")
		)
		(fp_line
			(start -0.750062 -1.560068)
			(end 0.750062 -1.560068)
			(stroke
				(width 0.1)
				(type default)
			)
			(layer "F.Fab")
		)
		(fp_line
			(start 0.750062 -1.560068)
			(end 0.750062 1.560068)
			(stroke
				(width 0.1)
				(type default)
			)
			(layer "F.Fab")
		)
		(pad "D" smd rect
			(at 1.100074 0 180)
			(size 1.016 1.4224)
			(layers "F.Cu" "F.Mask" "F.Paste")
			(net "SSD13_LED_ISO_N")
		)
		(pad "G" smd rect
			(at -1.100074 -0.94996 180)
			(size 1.016 1.4224)
			(layers "F.Cu" "F.Mask" "F.Paste")
			(net "SSD13_LED_R")
		)
		(pad "S" smd rect
			(at -1.100074 0.94996 180)
			(size 1.016 1.4224)
			(layers "F.Cu" "F.Mask" "F.Paste")
			(net "GND")
		)
	)
	(footprint ""
		(layer "F.Cu")
		(at 38.608 -160.380934)
		(property "Reference" "R23"
			(at 0 0 0)
			(layer "F.SilkS")
			(hide yes)
			(effects
				(font
					(size 1.27 1.27)
				)
			)
		)
		(property "Value" ""
			(at 0 0 0)
			(layer "F.Fab")
			(effects
				(font
					(size 1.27 1.27)
				)
			)
		)
		(duplicate_pad_numbers_are_jumpers no)
		(fp_line
			(start -0.7874 -0.4064)
			(end 0.7874 -0.4064)
			(stroke
				(width 0.1524)
				(type default)
			)
			(layer "F.SilkS")
		)
		(fp_line
			(start -0.7874 0.4064)
			(end -0.7874 -0.4064)
			(stroke
				(width 0.1524)
				(type default)
			)
			(layer "F.SilkS")
		)
		(fp_line
			(start 0.7874 -0.4064)
			(end 0.7874 0.4064)
			(stroke
				(width 0.1524)
				(type default)
			)
			(layer "F.SilkS")
		)
		(fp_line
			(start 0.7874 0.4064)
			(end -0.7874 0.4064)
			(stroke
				(width 0.1524)
				(type default)
			)
			(layer "F.SilkS")
		)
		(fp_line
			(start -0.67945 -0.305054)
			(end -0.12065 -0.305054)
			(stroke
				(width 0.1)
				(type default)
			)
			(layer "F.Fab")
		)
		(fp_line
			(start -0.67945 0.3048)
			(end -0.67945 -0.305054)
			(stroke
				(width 0.1)
				(type default)
			)
			(layer "F.Fab")
		)
		(fp_line
			(start -0.12065 -0.305054)
			(end -0.12065 -0.2794)
			(stroke
				(width 0.1)
				(type default)
			)
			(layer "F.Fab")
		)
		(fp_line
			(start -0.12065 -0.2794)
			(end 0.12065 -0.2794)
			(stroke
				(width 0.1)
				(type default)
			)
			(layer "F.Fab")
		)
		(fp_line
			(start -0.12065 0.2794)
			(end -0.12065 0.3048)
			(stroke
				(width 0.1)
				(type default)
			)
			(layer "F.Fab")
		)
		(fp_line
			(start -0.12065 0.3048)
			(end -0.67945 0.3048)
			(stroke
				(width 0.1)
				(type default)
			)
			(layer "F.Fab")
		)
		(fp_line
			(start 0.120396 0.2794)
			(end -0.12065 0.2794)
			(stroke
				(width 0.1)
				(type default)
			)
			(layer "F.Fab")
		)
		(fp_line
			(start 0.120396 0.3048)
			(end 0.120396 0.2794)
			(stroke
				(width 0.1)
				(type default)
			)
			(layer "F.Fab")
		)
		(fp_line
			(start 0.12065 -0.3048)
			(end 0.67945 -0.3048)
			(stroke
				(width 0.1)
				(type default)
			)
			(layer "F.Fab")
		)
		(fp_line
			(start 0.12065 -0.2794)
			(end 0.12065 -0.3048)
			(stroke
				(width 0.1)
				(type default)
			)
			(layer "F.Fab")
		)
		(fp_line
			(start 0.67945 -0.3048)
			(end 0.67945 0.3048)
			(stroke
				(width 0.1)
				(type default)
			)
			(layer "F.Fab")
		)
		(fp_line
			(start 0.67945 0.3048)
			(end 0.120396 0.3048)
			(stroke
				(width 0.1)
				(type default)
			)
			(layer "F.Fab")
		)
		(pad "1" smd circle
			(at -0.40005 0)
			(size 0 0)
			(layers "F.Cu" "F.Mask" "F.Paste")
			(net "NIC0_MAIN_PWR_EN")
		)
		(pad "2" smd circle
			(at 0.40005 0)
			(size 0 0)
			(layers "F.Cu" "F.Mask" "F.Paste")
			(net "GND")
		)
	)
	(footprint ""
		(layer "F.Cu")
		(at 141.931644 -390.171686 -90)
		(property "Reference" "R4106"
			(at 0 0 270)
			(layer "F.SilkS")
			(hide yes)
			(effects
				(font
					(size 1.27 1.27)
				)
			)
		)
		(property "Value" ""
			(at 0 0 270)
			(layer "F.Fab")
			(effects
				(font
					(size 1.27 1.27)
				)
			)
		)
		(duplicate_pad_numbers_are_jumpers no)
		(fp_line
			(start -0.7874 0.4064)
			(end -0.7874 -0.4064)
			(stroke
				(width 0.1524)
				(type default)
			)
			(layer "F.SilkS")
		)
		(fp_line
			(start 0.7874 0.4064)
			(end -0.7874 0.4064)
			(stroke
				(width 0.1524)
				(type default)
			)
			(layer "F.SilkS")
		)
		(fp_line
			(start -0.7874 -0.4064)
			(end 0.7874 -0.4064)
			(stroke
				(width 0.1524)
				(type default)
			)
			(layer "F.SilkS")
		)
		(fp_line
			(start 0.7874 -0.4064)
			(end 0.7874 0.4064)
			(stroke
				(width 0.1524)
				(type default)
			)
			(layer "F.SilkS")
		)
		(fp_line
			(start -0.67945 0.3048)
			(end -0.67945 -0.305054)
			(stroke
				(width 0.1)
				(type default)
			)
			(layer "F.Fab")
		)
		(fp_line
			(start -0.12065 0.3048)
			(end -0.67945 0.3048)
			(stroke
				(width 0.1)
				(type default)
			)
			(layer "F.Fab")
		)
		(fp_line
			(start 0.120396 0.3048)
			(end 0.120396 0.2794)
			(stroke
				(width 0.1)
				(type default)
			)
			(layer "F.Fab")
		)
		(fp_line
			(start 0.67945 0.3048)
			(end 0.120396 0.3048)
			(stroke
				(width 0.1)
				(type default)
			)
			(layer "F.Fab")
		)
		(fp_line
			(start -0.12065 0.2794)
			(end -0.12065 0.3048)
			(stroke
				(width 0.1)
				(type default)
			)
			(layer "F.Fab")
		)
		(fp_line
			(start 0.120396 0.2794)
			(end -0.12065 0.2794)
			(stroke
				(width 0.1)
				(type default)
			)
			(layer "F.Fab")
		)
		(fp_line
			(start -0.12065 -0.2794)
			(end 0.12065 -0.2794)
			(stroke
				(width 0.1)
				(type default)
			)
			(layer "F.Fab")
		)
		(fp_line
			(start 0.12065 -0.2794)
			(end 0.12065 -0.3048)
			(stroke
				(width 0.1)
				(type default)
			)
			(layer "F.Fab")
		)
		(fp_line
			(start 0.12065 -0.3048)
			(end 0.67945 -0.3048)
			(stroke
				(width 0.1)
				(type default)
			)
			(layer "F.Fab")
		)
		(fp_line
			(start 0.67945 -0.3048)
			(end 0.67945 0.3048)
			(stroke
				(width 0.1)
				(type default)
			)
			(layer "F.Fab")
		)
		(fp_line
			(start -0.67945 -0.305054)
			(end -0.12065 -0.305054)
			(stroke
				(width 0.1)
				(type default)
			)
			(layer "F.Fab")
		)
		(fp_line
			(start -0.12065 -0.305054)
			(end -0.12065 -0.2794)
			(stroke
				(width 0.1)
				(type default)
			)
			(layer "F.Fab")
		)
		(pad "1" smd circle
			(at -0.40005 0 270)
			(size 0 0)
			(layers "F.Cu" "F.Mask" "F.Paste")
			(net "SMB_MB_BMC_SDA")
		)
		(pad "2" smd circle
			(at 0.40005 0 270)
			(size 0 0)
			(layers "F.Cu" "F.Mask" "F.Paste")
			(net "SMB_MB_BMC_R_SDA")
		)
	)
	(footprint ""
		(layer "F.Cu")
		(at 252.971046 -145.189956 180)
		(property "Reference" "R734"
			(at 0 0 180)
			(layer "F.SilkS")
			(hide yes)
			(effects
				(font
					(size 1.27 1.27)
				)
			)
		)
		(property "Value" ""
			(at 0 0 180)
			(layer "F.Fab")
			(effects
				(font
					(size 1.27 1.27)
				)
			)
		)
		(duplicate_pad_numbers_are_jumpers no)
		(fp_line
			(start 0.7874 0.4064)
			(end -0.7874 0.4064)
			(stroke
				(width 0.1524)
				(type default)
			)
			(layer "F.SilkS")
		)
		(fp_line
			(start 0.7874 -0.4064)
			(end 0.7874 0.4064)
			(stroke
				(width 0.1524)
				(type default)
			)
			(layer "F.SilkS")
		)
		(fp_line
			(start -0.7874 0.4064)
			(end -0.7874 -0.4064)
			(stroke
				(width 0.1524)
				(type default)
			)
			(layer "F.SilkS")
		)
		(fp_line
			(start -0.7874 -0.4064)
			(end 0.7874 -0.4064)
			(stroke
				(width 0.1524)
				(type default)
			)
			(layer "F.SilkS")
		)
		(fp_line
			(start 0.67945 0.3048)
			(end 0.120396 0.3048)
			(stroke
				(width 0.1)
				(type default)
			)
			(layer "F.Fab")
		)
		(fp_line
			(start 0.67945 -0.3048)
			(end 0.67945 0.3048)
			(stroke
				(width 0.1)
				(type default)
			)
			(layer "F.Fab")
		)
		(fp_line
			(start 0.12065 -0.2794)
			(end 0.12065 -0.3048)
			(stroke
				(width 0.1)
				(type default)
			)
			(layer "F.Fab")
		)
		(fp_line
			(start 0.12065 -0.3048)
			(end 0.67945 -0.3048)
			(stroke
				(width 0.1)
				(type default)
			)
			(layer "F.Fab")
		)
		(fp_line
			(start 0.120396 0.3048)
			(end 0.120396 0.2794)
			(stroke
				(width 0.1)
				(type default)
			)
			(layer "F.Fab")
		)
		(fp_line
			(start 0.120396 0.2794)
			(end -0.12065 0.2794)
			(stroke
				(width 0.1)
				(type default)
			)
			(layer "F.Fab")
		)
		(fp_line
			(start -0.12065 0.3048)
			(end -0.67945 0.3048)
			(stroke
				(width 0.1)
				(type default)
			)
			(layer "F.Fab")
		)
		(fp_line
			(start -0.12065 0.2794)
			(end -0.12065 0.3048)
			(stroke
				(width 0.1)
				(type default)
			)
			(layer "F.Fab")
		)
		(fp_line
			(start -0.12065 -0.2794)
			(end 0.12065 -0.2794)
			(stroke
				(width 0.1)
				(type default)
			)
			(layer "F.Fab")
		)
		(fp_line
			(start -0.12065 -0.305054)
			(end -0.12065 -0.2794)
			(stroke
				(width 0.1)
				(type default)
			)
			(layer "F.Fab")
		)
		(fp_line
			(start -0.67945 0.3048)
			(end -0.67945 -0.305054)
			(stroke
				(width 0.1)
				(type default)
			)
			(layer "F.Fab")
		)
		(fp_line
			(start -0.67945 -0.305054)
			(end -0.12065 -0.305054)
			(stroke
				(width 0.1)
				(type default)
			)
			(layer "F.Fab")
		)
		(pad "1" smd circle
			(at -0.40005 0 180)
			(size 0 0)
			(layers "F.Cu" "F.Mask" "F.Paste")
			(net "P12V_NIC4")
		)
		(pad "2" smd circle
			(at 0.40005 0 180)
			(size 0 0)
			(layers "F.Cu" "F.Mask" "F.Paste")
			(net "P12V_NIC4_VIN_N")
		)
	)
	(footprint ""
		(layer "F.Cu")
		(at 119.084344 -137.565638 -90)
		(property "Reference" "PC36"
			(at 0 0 270)
			(layer "F.SilkS")
			(hide yes)
			(effects
				(font
					(size 1.27 1.27)
				)
			)
		)
		(property "Value" ""
			(at 0 0 270)
			(layer "F.Fab")
			(effects
				(font
					(size 1.27 1.27)
				)
			)
		)
		(duplicate_pad_numbers_are_jumpers no)
		(fp_line
			(start -0.7874 0.4064)
			(end -0.7874 -0.4064)
			(stroke
				(width 0.1524)
				(type default)
			)
			(layer "F.SilkS")
		)
		(fp_line
			(start 0.7874 0.4064)
			(end -0.7874 0.4064)
			(stroke
				(width 0.1524)
				(type default)
			)
			(layer "F.SilkS")
		)
		(fp_line
			(start -0.7874 -0.4064)
			(end 0.7874 -0.4064)
			(stroke
				(width 0.1524)
				(type default)
			)
			(layer "F.SilkS")
		)
		(fp_line
			(start 0.7874 -0.4064)
			(end 0.7874 0.4064)
			(stroke
				(width 0.1524)
				(type default)
			)
			(layer "F.SilkS")
		)
		(fp_line
			(start -0.67945 0.3048)
			(end -0.67945 -0.305054)
			(stroke
				(width 0.1)
				(type default)
			)
			(layer "F.Fab")
		)
		(fp_line
			(start -0.12065 0.3048)
			(end -0.67945 0.3048)
			(stroke
				(width 0.1)
				(type default)
			)
			(layer "F.Fab")
		)
		(fp_line
			(start 0.120396 0.3048)
			(end 0.120396 0.2794)
			(stroke
				(width 0.1)
				(type default)
			)
			(layer "F.Fab")
		)
		(fp_line
			(start 0.67945 0.3048)
			(end 0.120396 0.3048)
			(stroke
				(width 0.1)
				(type default)
			)
			(layer "F.Fab")
		)
		(fp_line
			(start -0.12065 0.2794)
			(end -0.12065 0.3048)
			(stroke
				(width 0.1)
				(type default)
			)
			(layer "F.Fab")
		)
		(fp_line
			(start 0.120396 0.2794)
			(end -0.12065 0.2794)
			(stroke
				(width 0.1)
				(type default)
			)
			(layer "F.Fab")
		)
		(fp_line
			(start -0.12065 -0.2794)
			(end 0.12065 -0.2794)
			(stroke
				(width 0.1)
				(type default)
			)
			(layer "F.Fab")
		)
		(fp_line
			(start 0.12065 -0.2794)
			(end 0.12065 -0.3048)
			(stroke
				(width 0.1)
				(type default)
			)
			(layer "F.Fab")
		)
		(fp_line
			(start 0.12065 -0.3048)
			(end 0.67945 -0.3048)
			(stroke
				(width 0.1)
				(type default)
			)
			(layer "F.Fab")
		)
		(fp_line
			(start 0.67945 -0.3048)
			(end 0.67945 0.3048)
			(stroke
				(width 0.1)
				(type default)
			)
			(layer "F.Fab")
		)
		(fp_line
			(start -0.67945 -0.305054)
			(end -0.12065 -0.305054)
			(stroke
				(width 0.1)
				(type default)
			)
			(layer "F.Fab")
		)
		(fp_line
			(start -0.12065 -0.305054)
			(end -0.12065 -0.2794)
			(stroke
				(width 0.1)
				(type default)
			)
			(layer "F.Fab")
		)
		(pad "1" smd circle
			(at -0.40005 0 270)
			(size 0 0)
			(layers "F.Cu" "F.Mask" "F.Paste")
			(net "P3V3_AUX")
		)
		(pad "2" smd circle
			(at 0.40005 0 270)
			(size 0 0)
			(layers "F.Cu" "F.Mask" "F.Paste")
			(net "GND")
		)
	)
	(footprint ""
		(layer "F.Cu")
		(at 199.399906 -393.100052)
		(property "Reference" "H58"
			(at -4.9784 -4.985766 0)
			(unlocked yes)
			(layer "F.SilkS")
			(effects
				(font
					(size 0.7874 0.5842)
					(thickness 0.1524)
				)
				(justify left)
			)
		)
		(property "Value" ""
			(at 0 0 0)
			(layer "F.Fab")
			(effects
				(font
					(size 1.27 1.27)
				)
			)
		)
		(duplicate_pad_numbers_are_jumpers no)
		(pad "1" thru_hole circle
			(at 0 0)
			(size 10.0076 10.0076)
			(drill 5.6134)
			(layers "*.Cu" "*.Mask")
			(remove_unused_layers no)
			(net "GND")
			(clearance -1.9431)
		)
	)
	(footprint ""
		(layer "F.Cu")
		(at 270.807942 -156.3624 180)
		(property "Reference" "R217"
			(at 0 0 180)
			(layer "F.SilkS")
			(hide yes)
			(effects
				(font
					(size 1.27 1.27)
				)
			)
		)
		(property "Value" ""
			(at 0 0 180)
			(layer "F.Fab")
			(effects
				(font
					(size 1.27 1.27)
				)
			)
		)
		(duplicate_pad_numbers_are_jumpers no)
		(fp_line
			(start 0.7874 0.4064)
			(end -0.7874 0.4064)
			(stroke
				(width 0.1524)
				(type default)
			)
			(layer "F.SilkS")
		)
		(fp_line
			(start 0.7874 -0.4064)
			(end 0.7874 0.4064)
			(stroke
				(width 0.1524)
				(type default)
			)
			(layer "F.SilkS")
		)
		(fp_line
			(start -0.7874 0.4064)
			(end -0.7874 -0.4064)
			(stroke
				(width 0.1524)
				(type default)
			)
			(layer "F.SilkS")
		)
		(fp_line
			(start -0.7874 -0.4064)
			(end 0.7874 -0.4064)
			(stroke
				(width 0.1524)
				(type default)
			)
			(layer "F.SilkS")
		)
		(fp_line
			(start 0.67945 0.3048)
			(end 0.120396 0.3048)
			(stroke
				(width 0.1)
				(type default)
			)
			(layer "F.Fab")
		)
		(fp_line
			(start 0.67945 -0.3048)
			(end 0.67945 0.3048)
			(stroke
				(width 0.1)
				(type default)
			)
			(layer "F.Fab")
		)
		(fp_line
			(start 0.12065 -0.2794)
			(end 0.12065 -0.3048)
			(stroke
				(width 0.1)
				(type default)
			)
			(layer "F.Fab")
		)
		(fp_line
			(start 0.12065 -0.3048)
			(end 0.67945 -0.3048)
			(stroke
				(width 0.1)
				(type default)
			)
			(layer "F.Fab")
		)
		(fp_line
			(start 0.120396 0.3048)
			(end 0.120396 0.2794)
			(stroke
				(width 0.1)
				(type default)
			)
			(layer "F.Fab")
		)
		(fp_line
			(start 0.120396 0.2794)
			(end -0.12065 0.2794)
			(stroke
				(width 0.1)
				(type default)
			)
			(layer "F.Fab")
		)
		(fp_line
			(start -0.12065 0.3048)
			(end -0.67945 0.3048)
			(stroke
				(width 0.1)
				(type default)
			)
			(layer "F.Fab")
		)
		(fp_line
			(start -0.12065 0.2794)
			(end -0.12065 0.3048)
			(stroke
				(width 0.1)
				(type default)
			)
			(layer "F.Fab")
		)
		(fp_line
			(start -0.12065 -0.2794)
			(end 0.12065 -0.2794)
			(stroke
				(width 0.1)
				(type default)
			)
			(layer "F.Fab")
		)
		(fp_line
			(start -0.12065 -0.305054)
			(end -0.12065 -0.2794)
			(stroke
				(width 0.1)
				(type default)
			)
			(layer "F.Fab")
		)
		(fp_line
			(start -0.67945 0.3048)
			(end -0.67945 -0.305054)
			(stroke
				(width 0.1)
				(type default)
			)
			(layer "F.Fab")
		)
		(fp_line
			(start -0.67945 -0.305054)
			(end -0.12065 -0.305054)
			(stroke
				(width 0.1)
				(type default)
			)
			(layer "F.Fab")
		)
		(pad "1" smd circle
			(at -0.40005 0 180)
			(size 0 0)
			(layers "F.Cu" "F.Mask" "F.Paste")
			(net "NIC4_DATA_OUT")
		)
		(pad "2" smd circle
			(at 0.40005 0 180)
			(size 0 0)
			(layers "F.Cu" "F.Mask" "F.Paste")
			(net "GND")
		)
	)
)
